(kicad_pcb
	(version 20260206)
	(generator "pcbnew")
	(generator_version "10.0")
	(general
		(thickness 1.6)
		(legacy_teardrops no)
	)
	(paper "A4")
	(title_block
		(title "v1-chassis-manager — T6M_CM_d_v01_1031_1645.brd")
		(comment 1 "Open CloudServer (Microsoft) / footprints 827-835 of 2512")
	)
	(layers
		(0 "F.Cu" signal "TOP")
		(4 "In1.Cu" signal "GND1")
		(6 "In2.Cu" signal "IN1")
		(8 "In3.Cu" signal "VCC1")
		(10 "In4.Cu" signal "VCC2")
		(12 "In5.Cu" signal "GND2")
		(14 "In6.Cu" signal "IN2")
		(16 "In7.Cu" signal "IN3")
		(18 "In8.Cu" signal "GND3")
		(2 "B.Cu" signal "BOTTOM")
		(9 "F.Adhes" user "F.Adhesive")
		(11 "B.Adhes" user "B.Adhesive")
		(13 "F.Paste" user "Package Geometry/Pastemask Top")
		(15 "B.Paste" user "Package Geometry/Pastemask Bottom")
		(5 "F.SilkS" user "Ref Des/Silkscreen Top")
		(7 "B.SilkS" user "Ref Des/Silkscreen Bottom")
		(1 "F.Mask" user "Board Geometry/Soldermask Top")
		(3 "B.Mask" user "Board Geometry/Soldermask Bottom")
		(17 "Dwgs.User" user "User.Drawings")
		(19 "Cmts.User" user "User.Comments")
		(21 "Eco1.User" user "User.Eco1")
		(23 "Eco2.User" user "User.Eco2")
		(25 "Edge.Cuts" user "Board Geometry/Outline")
		(27 "Margin" user)
		(31 "F.CrtYd" user "Package Geometry/Place Bound Top")
		(29 "B.CrtYd" user "Package Geometry/Place Bound Bottom")
		(35 "F.Fab" user "Ref Des/Assembly Top")
		(33 "B.Fab" user "Ref Des/Assembly Bottom")
	)
	(footprint ""
		(layer "F.Cu")
		(at 35.243008 -187.636404)
		(property "Reference" "C770"
			(at -1.53162 -5.211064 0)
			(unlocked yes)
			(layer "F.SilkS")
			(effects
				(font
					(size 0.7874 0.5842)
					(thickness 0.1524)
				)
				(justify left)
			)
		)
		(property "Value" ""
			(at 0 0 0)
			(layer "F.Fab")
			(effects
				(font
					(size 1.27 1.27)
				)
			)
		)
		(duplicate_pad_numbers_are_jumpers no)
		(fp_line
			(start -0.7874 -0.4064)
			(end 0.7874 -0.4064)
			(stroke
				(width 0.1524)
				(type default)
			)
			(layer "F.SilkS")
		)
		(fp_line
			(start -0.7874 0.4064)
			(end -0.7874 -0.4064)
			(stroke
				(width 0.1524)
				(type default)
			)
			(layer "F.SilkS")
		)
		(fp_line
			(start 0 0.381)
			(end 0 -0.381)
			(stroke
				(width 0.1524)
				(type default)
			)
			(layer "F.SilkS")
		)
		(fp_line
			(start 0.7874 -0.4064)
			(end 0.7874 0.4064)
			(stroke
				(width 0.1524)
				(type default)
			)
			(layer "F.SilkS")
		)
		(fp_line
			(start 0.7874 0.4064)
			(end -0.7874 0.4064)
			(stroke
				(width 0.1524)
				(type default)
			)
			(layer "F.SilkS")
		)
		(fp_poly
			(pts
				(xy -0.5334 0.254) (xy -0.635 0.254) (xy -0.635 0.2286) (xy -0.635 -0.254) (xy -0.5334 -0.254) (xy -0.5334 -0.2794)
				(xy 0.5334 -0.2794) (xy 0.5334 -0.254) (xy 0.635 -0.254) (xy 0.635 0.254) (xy 0.5334 0.254) (xy 0.5334 0.2794)
				(xy -0.508 0.2794) (xy -0.5334 0.2794)
			)
			(stroke
				(width 0)
				(type default)
			)
			(fill no)
			(layer "F.CrtYd")
		)
		(pad "1" smd rect
			(at 0.40005 0)
			(size 0.4572 0.508)
			(layers "F.Cu" "F.Mask" "F.Paste")
			(net "P12V_PDB")
		)
		(pad "2" smd rect
			(at -0.40005 0)
			(size 0.4572 0.508)
			(layers "F.Cu" "F.Mask" "F.Paste")
			(net "GND")
		)
	)
	(footprint ""
		(layer "F.Cu")
		(at 88.22055 -152.199848)
		(property "Reference" "PC39"
			(at -1.455166 4.218686 0)
			(unlocked yes)
			(layer "F.SilkS")
			(effects
				(font
					(size 0.7874 0.5842)
					(thickness 0.1524)
				)
				(justify left)
			)
		)
		(property "Value" ""
			(at 0 0 0)
			(layer "F.Fab")
			(effects
				(font
					(size 1.27 1.27)
				)
			)
		)
		(duplicate_pad_numbers_are_jumpers no)
		(fp_line
			(start -0.7874 -0.4064)
			(end 0.7874 -0.4064)
			(stroke
				(width 0.1524)
				(type default)
			)
			(layer "F.SilkS")
		)
		(fp_line
			(start -0.7874 0.4064)
			(end -0.7874 -0.4064)
			(stroke
				(width 0.1524)
				(type default)
			)
			(layer "F.SilkS")
		)
		(fp_line
			(start 0 0.381)
			(end 0 -0.381)
			(stroke
				(width 0.1524)
				(type default)
			)
			(layer "F.SilkS")
		)
		(fp_line
			(start 0.7874 -0.4064)
			(end 0.7874 0.4064)
			(stroke
				(width 0.1524)
				(type default)
			)
			(layer "F.SilkS")
		)
		(fp_line
			(start 0.7874 0.4064)
			(end -0.7874 0.4064)
			(stroke
				(width 0.1524)
				(type default)
			)
			(layer "F.SilkS")
		)
		(fp_poly
			(pts
				(xy -0.5334 0.254) (xy -0.635 0.254) (xy -0.635 0.2286) (xy -0.635 -0.254) (xy -0.5334 -0.254) (xy -0.5334 -0.2794)
				(xy 0.5334 -0.2794) (xy 0.5334 -0.254) (xy 0.635 -0.254) (xy 0.635 0.254) (xy 0.5334 0.254) (xy 0.5334 0.2794)
				(xy -0.508 0.2794) (xy -0.5334 0.2794)
			)
			(stroke
				(width 0)
				(type default)
			)
			(fill no)
			(layer "F.CrtYd")
		)
		(pad "1" smd rect
			(at 0.40005 0)
			(size 0.4572 0.508)
			(layers "F.Cu" "F.Mask" "F.Paste")
			(net "P1V8_STB_NODE1")
		)
		(pad "2" smd rect
			(at -0.40005 0)
			(size 0.4572 0.508)
			(layers "F.Cu" "F.Mask" "F.Paste")
			(net "GND")
		)
	)
	(footprint ""
		(layer "F.Cu")
		(at 12.73556 -138.620246 90)
		(property "Reference" "C554"
			(at -4.252468 -4.938522 90)
			(unlocked yes)
			(layer "F.SilkS")
			(effects
				(font
					(size 0.7874 0.5842)
					(thickness 0.1524)
				)
				(justify left)
			)
		)
		(property "Value" ""
			(at 0 0 90)
			(layer "F.Fab")
			(effects
				(font
					(size 1.27 1.27)
				)
			)
		)
		(duplicate_pad_numbers_are_jumpers no)
		(fp_line
			(start 0.7874 -0.4064)
			(end 0.7874 0.4064)
			(stroke
				(width 0.1524)
				(type default)
			)
			(layer "F.SilkS")
		)
		(fp_line
			(start -0.7874 -0.4064)
			(end 0.7874 -0.4064)
			(stroke
				(width 0.1524)
				(type default)
			)
			(layer "F.SilkS")
		)
		(fp_line
			(start 0 0.381)
			(end 0 -0.381)
			(stroke
				(width 0.1524)
				(type default)
			)
			(layer "F.SilkS")
		)
		(fp_line
			(start 0.7874 0.4064)
			(end -0.7874 0.4064)
			(stroke
				(width 0.1524)
				(type default)
			)
			(layer "F.SilkS")
		)
		(fp_line
			(start -0.7874 0.4064)
			(end -0.7874 -0.4064)
			(stroke
				(width 0.1524)
				(type default)
			)
			(layer "F.SilkS")
		)
		(fp_poly
			(pts
				(xy -0.5334 0.254) (xy -0.635 0.254) (xy -0.635 0.2286) (xy -0.635 -0.254) (xy -0.5334 -0.254) (xy -0.5334 -0.2794)
				(xy 0.5334 -0.2794) (xy 0.5334 -0.254) (xy 0.635 -0.254) (xy 0.635 0.254) (xy 0.5334 0.254) (xy 0.5334 0.2794)
				(xy -0.508 0.2794) (xy -0.5334 0.2794)
			)
			(stroke
				(width 0)
				(type default)
			)
			(fill no)
			(layer "F.CrtYd")
		)
		(pad "1" smd rect
			(at 0.40005 0 90)
			(size 0.4572 0.508)
			(layers "F.Cu" "F.Mask" "F.Paste")
			(net "N54310590")
		)
		(pad "2" smd rect
			(at -0.40005 0 90)
			(size 0.4572 0.508)
			(layers "F.Cu" "F.Mask" "F.Paste")
			(net "N54310592")
		)
	)
	(footprint ""
		(layer "F.Cu")
		(at 118.08968 -147.746466 180)
		(property "Reference" "R1038"
			(at 4.530344 -1.160018 0)
			(unlocked yes)
			(layer "F.SilkS")
			(effects
				(font
					(size 0.635 0.4064)
					(thickness 0.1524)
				)
				(justify left)
			)
		)
		(property "Value" ""
			(at 0 0 180)
			(layer "F.Fab")
			(effects
				(font
					(size 1.27 1.27)
				)
			)
		)
		(duplicate_pad_numbers_are_jumpers no)
		(fp_line
			(start 0.7874 0.4064)
			(end -0.7874 0.4064)
			(stroke
				(width 0.1524)
				(type default)
			)
			(layer "F.SilkS")
		)
		(fp_line
			(start 0.7874 -0.4064)
			(end 0.7874 0.4064)
			(stroke
				(width 0.1524)
				(type default)
			)
			(layer "F.SilkS")
		)
		(fp_line
			(start -0.7874 0.4064)
			(end -0.7874 -0.4064)
			(stroke
				(width 0.1524)
				(type default)
			)
			(layer "F.SilkS")
		)
		(fp_line
			(start -0.7874 -0.4064)
			(end 0.7874 -0.4064)
			(stroke
				(width 0.1524)
				(type default)
			)
			(layer "F.SilkS")
		)
		(fp_poly
			(pts
				(xy -0.508 0.2794) (xy -0.508 0.2286) (xy -0.635 0.2286) (xy -0.635 -0.254) (xy -0.5334 -0.254)
				(xy -0.5334 -0.2794) (xy 0.5334 -0.2794) (xy 0.5334 -0.254) (xy 0.635 -0.254) (xy 0.635 0.254) (xy 0.5334 0.254)
				(xy 0.5334 0.2794)
			)
			(stroke
				(width 0)
				(type default)
			)
			(fill no)
			(layer "F.CrtYd")
		)
		(pad "1" smd rect
			(at 0.40005 0 180)
			(size 0.4572 0.508)
			(layers "F.Cu" "F.Mask" "F.Paste")
			(net "GND")
		)
		(pad "2" smd rect
			(at -0.40005 0 180)
			(size 0.4572 0.508)
			(layers "F.Cu" "F.Mask" "F.Paste")
			(net "POWER_SW3_PWR_CTR_12V")
		)
	)
	(footprint ""
		(layer "F.Cu")
		(at 3.51028 -152.801066 180)
		(property "Reference" "U144"
			(at 2.377948 -0.985266 90)
			(unlocked yes)
			(layer "F.SilkS")
			(effects
				(font
					(size 0.7874 0.5842)
					(thickness 0.1524)
				)
			)
		)
		(property "Value" ""
			(at 0 0 180)
			(layer "F.Fab")
			(effects
				(font
					(size 1.27 1.27)
				)
			)
		)
		(duplicate_pad_numbers_are_jumpers no)
		(fp_line
			(start 1.651 1.905)
			(end -1.651 1.905)
			(stroke
				(width 0.1524)
				(type default)
			)
			(layer "F.SilkS")
		)
		(fp_line
			(start 1.651 -1.905)
			(end 1.651 1.905)
			(stroke
				(width 0.1524)
				(type default)
			)
			(layer "F.SilkS")
		)
		(fp_line
			(start -1.651 1.905)
			(end -1.651 -1.905)
			(stroke
				(width 0.1524)
				(type default)
			)
			(layer "F.SilkS")
		)
		(fp_line
			(start -1.651 -1.905)
			(end 1.651 -1.905)
			(stroke
				(width 0.1524)
				(type default)
			)
			(layer "F.SilkS")
		)
		(fp_poly
			(pts
				(xy -1.524 0.7112) (xy -1.524 1.7526) (xy -0.508 1.7526) (xy -0.508 0.6985) (xy 0.508 0.6985) (xy 0.508 1.7526)
				(xy 1.524 1.7526) (xy 1.524 0.6985) (xy 1.524 -0.6985) (xy 0.508 -0.6985) (xy 0.508 -1.7526) (xy -0.508 -1.7526)
				(xy -0.508 -0.6985) (xy -1.524 -0.6985) (xy -1.524 0.6985)
			)
			(stroke
				(width 0)
				(type default)
			)
			(fill no)
			(layer "F.CrtYd")
		)
		(fp_text user "S"
			(at 2.02692 1.562354 0)
			(unlocked yes)
			(layer "F.SilkS")
			(effects
				(font
					(size 0.635 0.4064)
					(thickness 0.1524)
				)
			)
		)
		(fp_text user "D"
			(at -1.4224 -2.422398 0)
			(unlocked yes)
			(layer "F.SilkS")
			(effects
				(font
					(size 0.635 0.4064)
					(thickness 0.1524)
				)
			)
		)
		(fp_text user "G"
			(at -2.23012 1.753616 0)
			(unlocked yes)
			(layer "F.SilkS")
			(effects
				(font
					(size 0.635 0.4064)
					(thickness 0.1524)
				)
			)
		)
		(pad "D" smd rect
			(at 0 -1.1176 180)
			(size 1.016 1.27)
			(layers "F.Cu" "F.Mask" "F.Paste")
			(net "UART_RI_P5_N")
		)
		(pad "G" smd rect
			(at -1.016 1.1176 180)
			(size 1.016 1.27)
			(layers "F.Cu" "F.Mask" "F.Paste")
			(net "TACKOVER_EN")
		)
		(pad "S" smd rect
			(at 1.016 1.1176 180)
			(size 1.016 1.27)
			(layers "F.Cu" "F.Mask" "F.Paste")
			(net "UART_RI_P5_LS_N")
		)
	)
	(footprint ""
		(layer "F.Cu")
		(at 111.871252 -165.50513 180)
		(property "Reference" "R677"
			(at 1.917192 12.305538 0)
			(unlocked yes)
			(layer "F.SilkS")
			(effects
				(font
					(size 0.7874 0.5842)
					(thickness 0.1524)
				)
				(justify left)
			)
		)
		(property "Value" ""
			(at 0 0 180)
			(layer "F.Fab")
			(effects
				(font
					(size 1.27 1.27)
				)
			)
		)
		(duplicate_pad_numbers_are_jumpers no)
		(fp_line
			(start 0.7874 0.4064)
			(end -0.7874 0.4064)
			(stroke
				(width 0.1524)
				(type default)
			)
			(layer "F.SilkS")
		)
		(fp_line
			(start 0.7874 -0.4064)
			(end 0.7874 0.4064)
			(stroke
				(width 0.1524)
				(type default)
			)
			(layer "F.SilkS")
		)
		(fp_line
			(start -0.7874 0.4064)
			(end -0.7874 -0.4064)
			(stroke
				(width 0.1524)
				(type default)
			)
			(layer "F.SilkS")
		)
		(fp_line
			(start -0.7874 -0.4064)
			(end 0.7874 -0.4064)
			(stroke
				(width 0.1524)
				(type default)
			)
			(layer "F.SilkS")
		)
		(fp_poly
			(pts
				(xy -0.508 0.2794) (xy -0.508 0.2286) (xy -0.635 0.2286) (xy -0.635 -0.254) (xy -0.5334 -0.254)
				(xy -0.5334 -0.2794) (xy 0.5334 -0.2794) (xy 0.5334 -0.254) (xy 0.635 -0.254) (xy 0.635 0.254) (xy 0.5334 0.254)
				(xy 0.5334 0.2794)
			)
			(stroke
				(width 0)
				(type default)
			)
			(fill no)
			(layer "F.CrtYd")
		)
		(pad "1" smd rect
			(at 0.40005 0 180)
			(size 0.4572 0.508)
			(layers "F.Cu" "F.Mask" "F.Paste")
			(net "P3V3_NODE1")
		)
		(pad "2" smd rect
			(at -0.40005 0 180)
			(size 0.4572 0.508)
			(layers "F.Cu" "F.Mask" "F.Paste")
			(net "PCA9535_INT_N")
		)
	)
	(footprint ""
		(layer "F.Cu")
		(at 89.030048 -128.998726 -90)
		(property "Reference" "R1259"
			(at 2.83591 -2.600198 90)
			(unlocked yes)
			(layer "F.SilkS")
			(effects
				(font
					(size 0.7874 0.5842)
					(thickness 0.1524)
				)
				(justify left)
			)
		)
		(property "Value" ""
			(at 0 0 270)
			(layer "F.Fab")
			(effects
				(font
					(size 1.27 1.27)
				)
			)
		)
		(duplicate_pad_numbers_are_jumpers no)
		(fp_line
			(start -0.7874 0.4064)
			(end -0.7874 -0.4064)
			(stroke
				(width 0.1524)
				(type default)
			)
			(layer "F.SilkS")
		)
		(fp_line
			(start 0.7874 0.4064)
			(end -0.7874 0.4064)
			(stroke
				(width 0.1524)
				(type default)
			)
			(layer "F.SilkS")
		)
		(fp_line
			(start -0.7874 -0.4064)
			(end 0.7874 -0.4064)
			(stroke
				(width 0.1524)
				(type default)
			)
			(layer "F.SilkS")
		)
		(fp_line
			(start 0.7874 -0.4064)
			(end 0.7874 0.4064)
			(stroke
				(width 0.1524)
				(type default)
			)
			(layer "F.SilkS")
		)
		(fp_poly
			(pts
				(xy -0.508 0.2794) (xy -0.508 0.2286) (xy -0.635 0.2286) (xy -0.635 -0.254) (xy -0.5334 -0.254)
				(xy -0.5334 -0.2794) (xy 0.5334 -0.2794) (xy 0.5334 -0.254) (xy 0.635 -0.254) (xy 0.635 0.254) (xy 0.5334 0.254)
				(xy 0.5334 0.2794)
			)
			(stroke
				(width 0)
				(type default)
			)
			(fill no)
			(layer "F.CrtYd")
		)
		(pad "1" smd rect
			(at 0.40005 0 270)
			(size 0.4572 0.508)
			(layers "F.Cu" "F.Mask" "F.Paste")
			(net "PORT80_LOUT7")
		)
		(pad "2" smd rect
			(at -0.40005 0 270)
			(size 0.4572 0.508)
			(layers "F.Cu" "F.Mask" "F.Paste")
			(net "N53313596")
		)
	)
	(footprint ""
		(layer "F.Cu")
		(at 176.238916 -35.59556 -90)
		(property "Reference" "D9"
			(at 0.390398 3.56616 0)
			(unlocked yes)
			(layer "F.SilkS")
			(effects
				(font
					(size 0.7874 0.5842)
					(thickness 0.1524)
				)
				(justify left)
			)
		)
		(property "Value" ""
			(at 0 0 270)
			(layer "F.Fab")
			(effects
				(font
					(size 1.27 1.27)
				)
			)
		)
		(duplicate_pad_numbers_are_jumpers no)
		(fp_line
			(start -0.450088 0.430022)
			(end 0.450088 0.430022)
			(stroke
				(width 0.1524)
				(type default)
			)
			(layer "F.SilkS")
		)
		(fp_line
			(start 0.450088 0.430022)
			(end 0.450088 -1.35001)
			(stroke
				(width 0.1524)
				(type default)
			)
			(layer "F.SilkS")
		)
		(fp_line
			(start -0.0762 -0.3556)
			(end 0.1016 -0.3556)
			(stroke
				(width 0.050038)
				(type default)
			)
			(layer "F.SilkS")
		)
		(fp_line
			(start 0.1016 -0.3556)
			(end 0.0127 -0.4699)
			(stroke
				(width 0.050038)
				(type default)
			)
			(layer "F.SilkS")
		)
		(fp_line
			(start 0.0127 -0.4699)
			(end -0.0762 -0.3556)
			(stroke
				(width 0.050038)
				(type default)
			)
			(layer "F.SilkS")
		)
		(fp_line
			(start -0.149098 -0.487172)
			(end 0.185674 -0.487172)
			(stroke
				(width 0.050038)
				(type default)
			)
			(layer "F.SilkS")
		)
		(fp_line
			(start 0.4064 -1.27)
			(end -0.381 -1.27)
			(stroke
				(width 0.1524)
				(type default)
			)
			(layer "F.SilkS")
		)
		(fp_line
			(start -0.2794 -1.2954)
			(end 0.4064 -1.27)
			(stroke
				(width 0.1524)
				(type default)
			)
			(layer "F.SilkS")
		)
		(fp_line
			(start -0.450088 -1.370076)
			(end -0.450088 0.430022)
			(stroke
				(width 0.1524)
				(type default)
			)
			(layer "F.SilkS")
		)
		(fp_line
			(start 0.450088 -1.370076)
			(end -0.450088 -1.370076)
			(stroke
				(width 0.1524)
				(type default)
			)
			(layer "F.SilkS")
		)
		(fp_poly
			(pts
				(xy -0.350012 -0.501142) (xy -0.350012 -0.348742) (xy -0.3556 -0.348742) (xy -0.3556 0.337058) (xy 0.3556 0.337058)
				(xy 0.3556 -0.348742) (xy 0.350012 -0.348742) (xy 0.350012 -0.475742) (xy 0.3556 -0.475742) (xy 0.3556 -1.186942)
				(xy -0.3556 -1.186942) (xy -0.3556 -0.501142)
			)
			(stroke
				(width 0)
				(type default)
			)
			(fill no)
			(layer "F.CrtYd")
		)
		(fp_line
			(start -0.350012 0.124968)
			(end 0.350012 0.124968)
			(stroke
				(width 0.1)
				(type default)
			)
			(layer "F.Fab")
		)
		(fp_line
			(start 0.350012 0.124968)
			(end 0.350012 -0.975106)
			(stroke
				(width 0.1)
				(type default)
			)
			(layer "F.Fab")
		)
		(fp_line
			(start -0.350012 -0.975106)
			(end -0.350012 0.124968)
			(stroke
				(width 0.1)
				(type default)
			)
			(layer "F.Fab")
		)
		(fp_line
			(start 0.350012 -0.975106)
			(end -0.350012 -0.975106)
			(stroke
				(width 0.1)
				(type default)
			)
			(layer "F.Fab")
		)
		(fp_text user "+"
			(at 1.317498 -0.51943 180)
			(unlocked yes)
			(layer "F.SilkS")
			(effects
				(font
					(size 1.6002 1.1938)
					(thickness 0.1524)
				)
				(justify left)
			)
		)
		(fp_text user "-"
			(at 0.737362 -2.518664 180)
			(unlocked yes)
			(layer "F.SilkS")
			(effects
				(font
					(size 1.6002 1.1938)
					(thickness 0.1524)
				)
				(justify left)
			)
		)
		(pad "A" smd rect
			(at 0 0)
			(size 0.5588 0.6096)
			(layers "F.Cu" "F.Mask" "F.Paste")
			(net "GND")
		)
		(pad "C" smd rect
			(at 0 -0.849884 180)
			(size 0.5588 0.6096)
			(layers "F.Cu" "F.Mask" "F.Paste")
			(net "USBPWR_P0")
		)
	)
	(footprint ""
		(layer "F.Cu")
		(at 119.61876 -188.126624 90)
		(property "Reference" "C745"
			(at 4.82092 -0.110998 90)
			(unlocked yes)
			(layer "F.SilkS")
			(effects
				(font
					(size 0.7874 0.5842)
					(thickness 0.1524)
				)
				(justify left)
			)
		)
		(property "Value" ""
			(at 0 0 90)
			(layer "F.Fab")
			(effects
				(font
					(size 1.27 1.27)
				)
			)
		)
		(duplicate_pad_numbers_are_jumpers no)
		(fp_line
			(start 0.7874 -0.4064)
			(end 0.7874 0.4064)
			(stroke
				(width 0.1524)
				(type default)
			)
			(layer "F.SilkS")
		)
		(fp_line
			(start -0.7874 -0.4064)
			(end 0.7874 -0.4064)
			(stroke
				(width 0.1524)
				(type default)
			)
			(layer "F.SilkS")
		)
		(fp_line
			(start 0 0.381)
			(end 0 -0.381)
			(stroke
				(width 0.1524)
				(type default)
			)
			(layer "F.SilkS")
		)
		(fp_line
			(start 0.7874 0.4064)
			(end -0.7874 0.4064)
			(stroke
				(width 0.1524)
				(type default)
			)
			(layer "F.SilkS")
		)
		(fp_line
			(start -0.7874 0.4064)
			(end -0.7874 -0.4064)
			(stroke
				(width 0.1524)
				(type default)
			)
			(layer "F.SilkS")
		)
		(fp_poly
			(pts
				(xy -0.5334 0.254) (xy -0.635 0.254) (xy -0.635 0.2286) (xy -0.635 -0.254) (xy -0.5334 -0.254) (xy -0.5334 -0.2794)
				(xy 0.5334 -0.2794) (xy 0.5334 -0.254) (xy 0.635 -0.254) (xy 0.635 0.254) (xy 0.5334 0.254) (xy 0.5334 0.2794)
				(xy -0.508 0.2794) (xy -0.5334 0.2794)
			)
			(stroke
				(width 0)
				(type default)
			)
			(fill no)
			(layer "F.CrtYd")
		)
		(pad "1" smd rect
			(at 0.40005 0 90)
			(size 0.4572 0.508)
			(layers "F.Cu" "F.Mask" "F.Paste")
			(net "UART_T8_NODE1_TXD_R")
		)
		(pad "2" smd rect
			(at -0.40005 0 90)
			(size 0.4572 0.508)
			(layers "F.Cu" "F.Mask" "F.Paste")
			(net "GND")
		)
	)
)
